FILE_TYPE = CONNECTIVITY;
{Allegro Design Entry HDL 17.4-2019 S026 (4007227) 1/17/2022}
"PAGE_NUMBER" = 32;
0"NC";
1"GND\g";
2"GND\g";
3"GND\g";
4"GND\g";
5"GND\g";
6"GND\g";
7"GND\g";
8"GND\g";
%"GENOA_SP5"
"34","(-7775,3450)","0","pure_quanta","I13";
;
LOCATION"U25"
$SEC"34"
CDS_SEC"34"
PART_TYPE"SMLF"
MATERIAL"IO"
VALUE"SOCKET6096_13568-001"
NEEDS_NO_SIZE"TRUE"
CDS_LMAN_SYM_OUTLINE"-400,3050,400,-3050"
CDS_LIB"pure_quanta"
PART_NUMBER"DGA^6000030";
"VSS_BV45"
$PN"BV45"2;
"VSS_BV44"
$PN"BV44"2;
"VSS_BV43"
$PN"BV43"2;
"VSS_BV39"
$PN"BV39"2;
"VSS_BV34"
$PN"BV34"2;
"VSS_BV33"
$PN"BV33"2;
"VSS_BV32"
$PN"BV32"2;
"VSS_BV31"
$PN"BV31"2;
"VSS_BV30"
$PN"BV30"2;
"VSS_BV29"
$PN"BV29"2;
"VSS_BV28"
$PN"BV28"2;
"VSS_BV27"
$PN"BV27"2;
"VSS_BV26"
$PN"BV26"2;
"VSS_BV25"
$PN"BV25"2;
"VSS_BV24"
$PN"BV24"2;
"VSS_BV23"
$PN"BV23"2;
"VSS_BV17"
$PN"BV17"2;
"VSS_BV15"
$PN"BV15"2;
"VSS_BV10"
$PN"BV10"2;
"VSS_BV8"
$PN"BV8"2;
"VSS_BV3"
$PN"BV3"2;
"VSS_BU75"
$PN"BU75"2;
"VSS_BU72"
$PN"BU72"2;
"VSS_BU70"
$PN"BU70"2;
"VSS_BU68"
$PN"BU68"2;
"VSS_BU65"
$PN"BU65"2;
"VSS_BU63"
$PN"BU63"2;
"VSS_BU61"
$PN"BU61"2;
"VSS_BU58"
$PN"BU58"2;
"VSS_BU56"
$PN"BU56"2;
"VSS_BU54"
$PN"BU54"2;
"VSS_BU51"
$PN"BU51"2;
"VSS_BU48"
$PN"BU48"2;
"VSS_BU45"
$PN"BU45"2;
"VSS_BU42"
$PN"BU42"2;
"VSS_BU41"
$PN"BU41"2;
"VSS_BU40"
$PN"BU40"2;
"VSS_BU36"
$PN"BU36"2;
"VSS_BU35"
$PN"BU35"2;
"VSS_BU34"
$PN"BU34"2;
"VSS_BU31"
$PN"BU31"2;
"VSS_BU28"
$PN"BU28"2;
"VSS_BU25"
$PN"BU25"2;
"VSS_BU22"
$PN"BU22"2;
"VSS_BU20"
$PN"BU20"2;
"VSS_BU18"
$PN"BU18"2;
"VSS_BU15"
$PN"BU15"2;
"VSS_BU13"
$PN"BU13"2;
"VSS_BU11"
$PN"BU11"2;
"VSS_BU8"
$PN"BU8"2;
"VSS_BU6"
$PN"BU6"2;
"VSS_BU4"
$PN"BU4"2;
"VSS_BU1"
$PN"BU1"2;
"VSS_BT73"
$PN"BT73"2;
"VSS_BT72"
$PN"BT72"2;
"VSS_BT71"
$PN"BT71"2;
"VSS_BT69"
$PN"BT69"2;
"VSS_BT68"
$PN"BT68"2;
"VSS_BT66"
$PN"BT66"2;
"VSS_BT65"
$PN"BT65"2;
"VSS_BT64"
$PN"BT64"2;
"VSS_BT62"
$PN"BT62"2;
"VSS_BT61"
$PN"BT61"2;
"VSS_BT59"
$PN"BT59"2;
"VSS_BT58"
$PN"BT58"2;
"VSS_BT57"
$PN"BT57"2;
"VSS_BT55"
$PN"BT55"2;
"VSS_BT54"
$PN"BT54"2;
"VSS_BT51"
$PN"BT51"2;
"VSS_BT48"
$PN"BT48"2;
"VSS_BT45"
$PN"BT45"2;
"VSS_BT42"
$PN"BT42"2;
"VSS_BT39"
$PN"BT39"2;
"VSS_BT37"
$PN"BT37"2;
"VSS_BT34"
$PN"BT34"2;
"VSS_BT31"
$PN"BT31"2;
"VSS_BT28"
$PN"BT28"2;
"VSS_BT25"
$PN"BT25"2;
"VSS_BT22"
$PN"BT22"2;
"VSS_BT21"
$PN"BT21"2;
"VSS_BT19"
$PN"BT19"2;
"VSS_BT18"
$PN"BT18"2;
"VSS_BT17"
$PN"BT17"2;
"VSS_BT15"
$PN"BT15"2;
"VSS_BT14"
$PN"BT14"2;
"VSS_BT12"
$PN"BT12"2;
"VSS_BT11"
$PN"BT11"2;
"VSS_BT10"
$PN"BT10"2;
"VSS_BT8"
$PN"BT8"2;
"VSS_BT7"
$PN"BT7"2;
"VSS_BT5"
$PN"BT5"2;
"VSS_BT4"
$PN"BT4"2;
"VSS_BT3"
$PN"BT3"2;
"VSS_BR75"
$PN"BR75"2;
"VSS_BR73"
$PN"BR73"2;
"VSS_BR70"
$PN"BR70"2;
"VSS_BR69"
$PN"BR69"2;
"VSS_BR68"
$PN"BR68"2;
"VSS_BR66"
$PN"BR66"2;
"VSS_BR63"
$PN"BR63"2;
"VSS_BR62"
$PN"BR62"2;
"VSS_BR61"
$PN"BR61"2;
"VSS_BR59"
$PN"BR59"2;
"VSS_BR56"
$PN"BR56"2;
"VSS_BR55"
$PN"BR55"2;
"VSS_BR51"
$PN"BR51"2;
"VSS_BR49"
$PN"BR49"2;
"VSS_BR47"
$PN"BR47"2;
"VSS_BR45"
$PN"BR45"2;
"VSS_BR43"
$PN"BR43"2;
"VSS_BR41"
$PN"BR41"2;
"VSS_BR36"
$PN"BR36"2;
"VSS_BR34"
$PN"BR34"2;
"VSS_BR32"
$PN"BR32"2;
"VSS_BR30"
$PN"BR30"2;
"VSS_BR28"
$PN"BR28"2;
"VSS_BR26"
$PN"BR26"2;
"VSS_BR24"
$PN"BR24"1;
"VSS_BR22"
$PN"BR22"1;
"VSS_BR21"
$PN"BR21"1;
"VSS_BR20"
$PN"BR20"1;
"VSS_BR17"
$PN"BR17"1;
"VSS_BR15"
$PN"BR15"1;
"VSS_BR14"
$PN"BR14"1;
"VSS_BR13"
$PN"BR13"1;
"VSS_BR10"
$PN"BR10"1;
"VSS_BR8"
$PN"BR8"1;
"VSS_BR7"
$PN"BR7"1;
"VSS_BR6"
$PN"BR6"1;
"VSS_BR3"
$PN"BR3"1;
"VSS_BR1"
$PN"BR1"1;
"VSS_BP73"
$PN"BP73"1;
"VSS_BP71"
$PN"BP71"1;
"VSS_BP68"
$PN"BP68"1;
"VSS_BP66"
$PN"BP66"1;
"VSS_BP64"
$PN"BP64"1;
"VSS_BP61"
$PN"BP61"1;
"VSS_BP59"
$PN"BP59"1;
"VSS_BP57"
$PN"BP57"1;
"VSS_BP54"
$PN"BP54"1;
"VSS_BP52"
$PN"BP52"1;
"VSS_BP50"
$PN"BP50"1;
"VSS_BP48"
$PN"BP48"1;
"VSS_BP46"
$PN"BP46"1;
"VSS_BP44"
$PN"BP44"1;
"VSS_BP42"
$PN"BP42"1;
"VSS_BP40"
$PN"BP40"1;
"VSS_BP37"
$PN"BP37"1;
"VSS_BP35"
$PN"BP35"1;
"VSS_BP33"
$PN"BP33"1;
"VSS_BP31"
$PN"BP31"1;
"VSS_BP29"
$PN"BP29"1;
"VSS_BP27"
$PN"BP27"1;
"VSS_BP25"
$PN"BP25"1;
"VSS_BP23"
$PN"BP23"1;
"VSS_BP19"
$PN"BP19"1;
"VSS_BP17"
$PN"BP17"1;
"VSS_BP15"
$PN"BP15"1;
"VSS_BP12"
$PN"BP12"1;
"VSS_BP10"
$PN"BP10"1;
"VSS_BP8"
$PN"BP8"1;
"VSS_BP5"
$PN"BP5"1;
"VSS_BP3"
$PN"BP3"1;
"VSS_BN75"
$PN"BN75"1;
"VSS_BN72"
$PN"BN72"1;
"VSS_BN70"
$PN"BN70"1;
"VSS_BN68"
$PN"BN68"1;
"VSS_BN65"
$PN"BN65"1;
"VSS_BN63"
$PN"BN63"1;
"VSS_BN61"
$PN"BN61"1;
"VSS_BN58"
$PN"BN58"1;
"VSS_BN56"
$PN"BN56"1;
"VSS_BN53"
$PN"BN53"1;
"VSS_BN51"
$PN"BN51"1;
"VSS_BN49"
$PN"BN49"1;
"VSS_BN47"
$PN"BN47"1;
"VSS_BN45"
$PN"BN45"1;
"VSS_BN43"
$PN"BN43"1;
"VSS_BN41"
$PN"BN41"1;
"VSS_BN36"
$PN"BN36"1;
"VSS_BN34"
$PN"BN34"1;
"VSS_BN32"
$PN"BN32"1;
"VSS_BN30"
$PN"BN30"1;
"VSS_BN28"
$PN"BN28"1;
"VSS_BN26"
$PN"BN26"1;
"VSS_BN24"
$PN"BN24"1;
"VSS_BN22"
$PN"BN22"1;
"VSS_BN20"
$PN"BN20"1;
"VSS_BN18"
$PN"BN18"1;
"VSS_BN15"
$PN"BN15"1;
"VSS_BN13"
$PN"BN13"1;
"VSS_BN11"
$PN"BN11"1;
"VSS_BN8"
$PN"BN8"1;
"VSS_BN6"
$PN"BN6"1;
"VSS_BN4"
$PN"BN4"1;
"VSS_BN1"
$PN"BN1"1;
"VSS_BM73"
$PN"BM73"1;
"VSS_BM68"
$PN"BM68"1;
"VSS_BM66"
$PN"BM66"1;
"VSS_BM61"
$PN"BM61"1;
"VSS_BM59"
$PN"BM59"1;
"VSS_BM54"
$PN"BM54"1;
"VSS_BM52"
$PN"BM52"1;
"VSS_BM50"
$PN"BM50"1;
"VSS_BM48"
$PN"BM48"1;
"VSS_BM46"
$PN"BM46"1;
"VSS_BM44"
$PN"BM44"1;
"VSS_BM42"
$PN"BM42"1;
"VSS_BM40"
$PN"BM40"1;
"VSS_BM37"
$PN"BM37"1;
"VSS_BM35"
$PN"BM35"1;
"VSS_BM33"
$PN"BM33"1;
"VSS_BM31"
$PN"BM31"1;
"VSS_BM29"
$PN"BM29"1;
"VSS_BM27"
$PN"BM27"1;
"VSS_BM25"
$PN"BM25"1;
"VSS_BM23"
$PN"BM23"1;
"VSS_BM17"
$PN"BM17"1;
"VSS_BM15"
$PN"BM15"1;
"VSS_BM10"
$PN"BM10"1;
"VSS_BM8"
$PN"BM8"1;
"VSS_BM3"
$PN"BM3"1;
"VSS_BL75"
$PN"BL75"1;
"VSS_BL72"
$PN"BL72"1;
"VSS_BL70"
$PN"BL70"1;
"VSS_BL68"
$PN"BL68"1;
"VSS_BL65"
$PN"BL65"1;
"VSS_BL63"
$PN"BL63"1;
"VSS_BL61"
$PN"BL61"1;
"VSS_BL58"
$PN"BL58"1;
"VSS_BL56"
$PN"BL56"1;
"VSS_BL53"
$PN"BL53"1;
"VSS_BL51"
$PN"BL51"1;
"VSS_BL49"
$PN"BL49"1;
"VSS_BL28"
$PN"BL28"1;
"VSS_BL26"
$PN"BL26"1;
"VSS_BV37"
$PN"BV37"2;
%"GENOA_SP5"
"37","(-5750,3450)","0","pure_quanta","I14";
;
LOCATION"U25"
$SEC"37"
CDS_SEC"37"
PART_TYPE"SMLF"
MATERIAL"IO"
VALUE"SOCKET6096_13568-001"
NEEDS_NO_SIZE"TRUE"
CDS_LMAN_SYM_OUTLINE"-400,3050,400,-3050"
CDS_LIB"pure_quanta"
PART_NUMBER"DGA^6000030";
"VSS_CF33"
$PN"CF33"4;
"VSS_CF32"
$PN"CF32"4;
"VSS_CF31"
$PN"CF31"4;
"VSS_CF30"
$PN"CF30"4;
"VSS_CF29"
$PN"CF29"4;
"VSS_CF28"
$PN"CF28"4;
"VSS_CF27"
$PN"CF27"4;
"VSS_CF26"
$PN"CF26"4;
"VSS_CF25"
$PN"CF25"4;
"VSS_CF24"
$PN"CF24"4;
"VSS_CF23"
$PN"CF23"4;
"VSS_CF19"
$PN"CF19"4;
"VSS_CF17"
$PN"CF17"4;
"VSS_CF15"
$PN"CF15"4;
"VSS_CF12"
$PN"CF12"4;
"VSS_CF10"
$PN"CF10"4;
"VSS_CF8"
$PN"CF8"4;
"VSS_CF5"
$PN"CF5"4;
"VSS_CF3"
$PN"CF3"4;
"VSS_CE75"
$PN"CE75"4;
"VSS_CE72"
$PN"CE72"4;
"VSS_CE70"
$PN"CE70"4;
"VSS_CE68"
$PN"CE68"4;
"VSS_CE65"
$PN"CE65"4;
"VSS_CE63"
$PN"CE63"4;
"VSS_CE61"
$PN"CE61"4;
"VSS_CE58"
$PN"CE58"4;
"VSS_CE56"
$PN"CE56"4;
"VSS_CE54"
$PN"CE54"4;
"VSS_CE51"
$PN"CE51"4;
"VSS_CE48"
$PN"CE48"4;
"VSS_CE45"
$PN"CE45"4;
"VSS_CE42"
$PN"CE42"4;
"VSS_CE41"
$PN"CE41"4;
"VSS_CE40"
$PN"CE40"4;
"VSS_CE36"
$PN"CE36"4;
"VSS_CE35"
$PN"CE35"4;
"VSS_CE34"
$PN"CE34"4;
"VSS_CE31"
$PN"CE31"4;
"VSS_CE28"
$PN"CE28"4;
"VSS_CE25"
$PN"CE25"4;
"VSS_CE22"
$PN"CE22"4;
"VSS_CE20"
$PN"CE20"4;
"VSS_CE18"
$PN"CE18"4;
"VSS_CE15"
$PN"CE15"4;
"VSS_CE13"
$PN"CE13"4;
"VSS_CE11"
$PN"CE11"4;
"VSS_CE8"
$PN"CE8"4;
"VSS_CE6"
$PN"CE6"4;
"VSS_CE4"
$PN"CE4"4;
"VSS_CE1"
$PN"CE1"4;
"VSS_CD73"
$PN"CD73"4;
"VSS_CD68"
$PN"CD68"4;
"VSS_CD66"
$PN"CD66"4;
"VSS_CD61"
$PN"CD61"4;
"VSS_CD59"
$PN"CD59"4;
"VSS_CD54"
$PN"CD54"4;
"VSS_CD51"
$PN"CD51"4;
"VSS_CD48"
$PN"CD48"4;
"VSS_CD45"
$PN"CD45"4;
"VSS_CD42"
$PN"CD42"4;
"VSS_CD39"
$PN"CD39"4;
"VSS_CD37"
$PN"CD37"4;
"VSS_CD34"
$PN"CD34"4;
"VSS_CD31"
$PN"CD31"4;
"VSS_CD28"
$PN"CD28"4;
"VSS_CD25"
$PN"CD25"4;
"VSS_CD22"
$PN"CD22"4;
"VSS_CD17"
$PN"CD17"4;
"VSS_CD15"
$PN"CD15"4;
"VSS_CD10"
$PN"CD10"4;
"VSS_CD8"
$PN"CD8"4;
"VSS_CD3"
$PN"CD3"4;
"VSS_CC75"
$PN"CC75"4;
"VSS_CC72"
$PN"CC72"4;
"VSS_CC70"
$PN"CC70"4;
"VSS_CC68"
$PN"CC68"4;
"VSS_CC65"
$PN"CC65"4;
"VSS_CC63"
$PN"CC63"4;
"VSS_CC61"
$PN"CC61"4;
"VSS_CC58"
$PN"CC58"4;
"VSS_CC56"
$PN"CC56"4;
"VSS_CC54"
$PN"CC54"4;
"VSS_CC51"
$PN"CC51"4;
"VSS_CC48"
$PN"CC48"4;
"VSS_CC45"
$PN"CC45"4;
"VSS_CC42"
$PN"CC42"4;
"VSS_CC34"
$PN"CC34"4;
"VSS_CC31"
$PN"CC31"4;
"VSS_CC28"
$PN"CC28"4;
"VSS_CC25"
$PN"CC25"4;
"VSS_CC20"
$PN"CC20"4;
"VSS_CC18"
$PN"CC18"4;
"VSS_CC15"
$PN"CC15"4;
"VSS_CC13"
$PN"CC13"4;
"VSS_CC11"
$PN"CC11"4;
"VSS_CC8"
$PN"CC8"4;
"VSS_CC6"
$PN"CC6"4;
"VSS_CC4"
$PN"CC4"4;
"VSS_CC1"
$PN"CC1"4;
"VSS_CB73"
$PN"CB73"4;
"VSS_CB71"
$PN"CB71"4;
"VSS_CB68"
$PN"CB68"4;
"VSS_CB66"
$PN"CB66"4;
"VSS_CB64"
$PN"CB64"4;
"VSS_CB61"
$PN"CB61"4;
"VSS_CB59"
$PN"CB59"4;
"VSS_CB57"
$PN"CB57"4;
"VSS_CB53"
$PN"CB53"4;
"VSS_CB52"
$PN"CB52"4;
"VSS_CB51"
$PN"CB51"4;
"VSS_CB50"
$PN"CB50"4;
"VSS_CB49"
$PN"CB49"4;
"VSS_CB48"
$PN"CB48"4;
"VSS_CB47"
$PN"CB47"4;
"VSS_CB46"
$PN"CB46"4;
"VSS_CB45"
$PN"CB45"4;
"VSS_CB43"
$PN"CB43"3;
"VSS_CB42"
$PN"CB42"3;
"VSS_CB39"
$PN"CB39"3;
"VSS_CB37"
$PN"CB37"3;
"VSS_CB34"
$PN"CB34"3;
"VSS_CB33"
$PN"CB33"3;
"VSS_CB32"
$PN"CB32"3;
"VSS_CB31"
$PN"CB31"3;
"VSS_CB30"
$PN"CB30"3;
"VSS_CB29"
$PN"CB29"3;
"VSS_CB28"
$PN"CB28"3;
"VSS_CB27"
$PN"CB27"3;
"VSS_CB26"
$PN"CB26"3;
"VSS_CB25"
$PN"CB25"3;
"VSS_CB24"
$PN"CB24"3;
"VSS_CB23"
$PN"CB23"3;
"VSS_CB19"
$PN"CB19"3;
"VSS_CB17"
$PN"CB17"3;
"VSS_CB15"
$PN"CB15"3;
"VSS_CB12"
$PN"CB12"3;
"VSS_CB10"
$PN"CB10"3;
"VSS_CB8"
$PN"CB8"3;
"VSS_CB5"
$PN"CB5"3;
"VSS_CB3"
$PN"CB3"3;
"VSS_CA75"
$PN"CA75"3;
"VSS_CA70"
$PN"CA70"3;
"VSS_CA68"
$PN"CA68"3;
"VSS_CA63"
$PN"CA63"3;
"VSS_CA61"
$PN"CA61"3;
"VSS_CA56"
$PN"CA56"3;
"VSS_CA54"
$PN"CA54"3;
"VSS_CA51"
$PN"CA51"3;
"VSS_CA48"
$PN"CA48"3;
"VSS_CA45"
$PN"CA45"3;
"VSS_CA42"
$PN"CA42"3;
"VSS_CA41"
$PN"CA41"3;
"VSS_CA40"
$PN"CA40"3;
"VSS_CA36"
$PN"CA36"3;
"VSS_CA35"
$PN"CA35"3;
"VSS_CA34"
$PN"CA34"3;
"VSS_CA31"
$PN"CA31"3;
"VSS_CA28"
$PN"CA28"3;
"VSS_CA25"
$PN"CA25"3;
"VSS_CA22"
$PN"CA22"3;
"VSS_CA20"
$PN"CA20"3;
"VSS_CA15"
$PN"CA15"3;
"VSS_CA13"
$PN"CA13"3;
"VSS_CA8"
$PN"CA8"3;
"VSS_CA6"
$PN"CA6"3;
"VSS_CA1"
$PN"CA1"3;
"VSS_BY73"
$PN"BY73"3;
"VSS_BY71"
$PN"BY71"3;
"VSS_BY68"
$PN"BY68"3;
"VSS_BY66"
$PN"BY66"3;
"VSS_BY64"
$PN"BY64"3;
"VSS_BY61"
$PN"BY61"3;
"VSS_BY59"
$PN"BY59"3;
"VSS_BY57"
$PN"BY57"3;
"VSS_BY54"
$PN"BY54"3;
"VSS_BY51"
$PN"BY51"3;
"VSS_BY48"
$PN"BY48"3;
"VSS_BY45"
$PN"BY45"3;
"VSS_BY42"
$PN"BY42"3;
"VSS_BY39"
$PN"BY39"3;
"VSS_BY37"
$PN"BY37"3;
"VSS_BY34"
$PN"BY34"3;
"VSS_BY31"
$PN"BY31"3;
"VSS_BY28"
$PN"BY28"3;
"VSS_BY25"
$PN"BY25"3;
"VSS_BY22"
$PN"BY22"3;
"VSS_BY19"
$PN"BY19"3;
"VSS_BY17"
$PN"BY17"3;
"VSS_BY15"
$PN"BY15"3;
"VSS_BY12"
$PN"BY12"3;
"VSS_BY10"
$PN"BY10"3;
"VSS_BY8"
$PN"BY8"3;
"VSS_BY5"
$PN"BY5"3;
"VSS_BY3"
$PN"BY3"3;
"VSS_BW75"
$PN"BW75"3;
"VSS_BW72"
$PN"BW72"3;
"VSS_BW70"
$PN"BW70"3;
"VSS_BW68"
$PN"BW68"3;
"VSS_BW65"
$PN"BW65"3;
"VSS_BW63"
$PN"BW63"3;
"VSS_BW61"
$PN"BW61"3;
"VSS_BW58"
$PN"BW58"3;
"VSS_BW56"
$PN"BW56"3;
"VSS_BW54"
$PN"BW54"3;
"VSS_BW51"
$PN"BW51"3;
"VSS_BW48"
$PN"BW48"3;
"VSS_BW45"
$PN"BW45"3;
"VSS_BW42"
$PN"BW42"3;
"VSS_BW34"
$PN"BW34"3;
"VSS_BW31"
$PN"BW31"3;
"VSS_BW28"
$PN"BW28"3;
"VSS_BW22"
$PN"BW22"3;
"VSS_BW20"
$PN"BW20"3;
"VSS_BW18"
$PN"BW18"3;
"VSS_BW15"
$PN"BW15"3;
"VSS_BW13"
$PN"BW13"3;
"VSS_BW11"
$PN"BW11"3;
"VSS_BW8"
$PN"BW8"3;
"VSS_BW6"
$PN"BW6"3;
"VSS_BW4"
$PN"BW4"3;
"VSS_BW1"
$PN"BW1"3;
"VSS_BV73"
$PN"BV73"3;
"VSS_BV68"
$PN"BV68"3;
"VSS_BV66"
$PN"BV66"3;
"VSS_BV61"
$PN"BV61"3;
"VSS_BV59"
$PN"BV59"3;
"VSS_BV53"
$PN"BV53"3;
"VSS_BV52"
$PN"BV52"3;
"VSS_BV51"
$PN"BV51"3;
"VSS_BV50"
$PN"BV50"3;
"VSS_BV49"
$PN"BV49"3;
"VSS_BV48"
$PN"BV48"3;
"VSS_BV47"
$PN"BV47"3;
"VSS_BV46"
$PN"BV46"3;
%"GENOA_SP5"
"38","(-3675,3425)","0","pure_quanta","I15";
;
LOCATION"U25"
$SEC"38"
CDS_SEC"38"
PART_TYPE"SMLF"
MATERIAL"IO"
VALUE"SOCKET6096_13568-001"
NEEDS_NO_SIZE"TRUE"
CDS_LMAN_SYM_OUTLINE"-400,3050,400,-3050"
CDS_LIB"pure_quanta"
PART_NUMBER"DGA^6000030";
"VSS_CP19"
$PN"CP19"6;
"VSS_CP17"
$PN"CP17"6;
"VSS_CP15"
$PN"CP15"6;
"VSS_CP12"
$PN"CP12"6;
"VSS_CP10"
$PN"CP10"6;
"VSS_CP8"
$PN"CP8"6;
"VSS_CP5"
$PN"CP5"6;
"VSS_CP3"
$PN"CP3"6;
"VSS_CN75"
$PN"CN75"6;
"VSS_CN70"
$PN"CN70"6;
"VSS_CN68"
$PN"CN68"6;
"VSS_CN63"
$PN"CN63"6;
"VSS_CN61"
$PN"CN61"6;
"VSS_CN51"
$PN"CN51"6;
"VSS_CN48"
$PN"CN48"6;
"VSS_CN45"
$PN"CN45"6;
"VSS_CN42"
$PN"CN42"6;
"VSS_CN34"
$PN"CN34"6;
"VSS_CN31"
$PN"CN31"6;
"VSS_CN28"
$PN"CN28"6;
"VSS_CN25"
$PN"CN25"6;
"VSS_CN15"
$PN"CN15"6;
"VSS_CN13"
$PN"CN13"6;
"VSS_CN8"
$PN"CN8"6;
"VSS_CN6"
$PN"CN6"6;
"VSS_CN1"
$PN"CN1"6;
"VSS_CM73"
$PN"CM73"6;
"VSS_CM71"
$PN"CM71"6;
"VSS_CM68"
$PN"CM68"6;
"VSS_CM59"
$PN"CM59"6;
"VSS_CM57"
$PN"CM57"6;
"VSS_CM53"
$PN"CM53"6;
"VSS_CM52"
$PN"CM52"6;
"VSS_CM51"
$PN"CM51"6;
"VSS_CM49"
$PN"CM49"6;
"VSS_CM48"
$PN"CM48"6;
"VSS_CM47"
$PN"CM47"6;
"VSS_CM46"
$PN"CM46"6;
"VSS_CM45"
$PN"CM45"6;
"VSS_CM44"
$PN"CM44"6;
"VSS_CM33"
$PN"CM33"6;
"VSS_CM32"
$PN"CM32"6;
"VSS_CM31"
$PN"CM31"6;
"VSS_CM30"
$PN"CM30"6;
"VSS_CM29"
$PN"CM29"6;
"VSS_CM28"
$PN"CM28"6;
"VSS_CM23"
$PN"CM23"6;
"VSS_CM19"
$PN"CM19"6;
"VSS_CM17"
$PN"CM17"6;
"VSS_CM15"
$PN"CM15"6;
"VSS_CM12"
$PN"CM12"6;
"VSS_CM10"
$PN"CM10"6;
"VSS_CM8"
$PN"CM8"6;
"VSS_CL72"
$PN"CL72"6;
"VSS_CL70"
$PN"CL70"6;
"VSS_CL68"
$PN"CL68"6;
"VSS_CL65"
$PN"CL65"6;
"VSS_CL63"
$PN"CL63"6;
"VSS_CL61"
$PN"CL61"6;
"VSS_CL58"
$PN"CL58"6;
"VSS_CL56"
$PN"CL56"6;
"VSS_CL48"
$PN"CL48"6;
"VSS_CL45"
$PN"CL45"6;
"VSS_CL42"
$PN"CL42"6;
"VSS_CL41"
$PN"CL41"6;
"VSS_CL40"
$PN"CL40"6;
"VSS_CL36"
$PN"CL36"6;
"VSS_CL35"
$PN"CL35"6;
"VSS_CL34"
$PN"CL34"6;
"VSS_CL31"
$PN"CL31"6;
"VSS_CL25"
$PN"CL25"6;
"VSS_CL22"
$PN"CL22"6;
"VSS_CL20"
$PN"CL20"6;
"VSS_CL18"
$PN"CL18"6;
"VSS_CL15"
$PN"CL15"6;
"VSS_CL13"
$PN"CL13"6;
"VSS_CL11"
$PN"CL11"6;
"VSS_CL8"
$PN"CL8"6;
"VSS_CL6"
$PN"CL6"6;
"VSS_CL4"
$PN"CL4"6;
"VSS_CL1"
$PN"CL1"6;
"VSS_CK73"
$PN"CK73"6;
"VSS_CK68"
$PN"CK68"6;
"VSS_CK66"
$PN"CK66"6;
"VSS_CK61"
$PN"CK61"6;
"VSS_CK59"
$PN"CK59"6;
"VSS_CK54"
$PN"CK54"6;
"VSS_CK53"
$PN"CK53"6;
"VSS_CK52"
$PN"CK52"6;
"VSS_CK51"
$PN"CK51"6;
"VSS_CK50"
$PN"CK50"6;
"VSS_CK49"
$PN"CK49"6;
"VSS_CK48"
$PN"CK48"6;
"VSS_CK45"
$PN"CK45"6;
"VSS_CK44"
$PN"CK44"6;
"VSS_CK43"
$PN"CK43"6;
"VSS_CK42"
$PN"CK42"5;
"VSS_CK39"
$PN"CK39"5;
"VSS_CK37"
$PN"CK37"5;
"VSS_CK34"
$PN"CK34"5;
"VSS_CK32"
$PN"CK32"5;
"VSS_CK28"
$PN"CK28"5;
"VSS_CK27"
$PN"CK27"5;
"VSS_CK26"
$PN"CK26"5;
"VSS_CK25"
$PN"CK25"5;
"VSS_CK24"
$PN"CK24"5;
"VSS_CK23"
$PN"CK23"5;
"VSS_CK22"
$PN"CK22"5;
"VSS_CK8"
$PN"CK8"5;
"VSS_CK3"
$PN"CK3"5;
"VSS_CJ75"
$PN"CJ75"5;
"VSS_CJ72"
$PN"CJ72"5;
"VSS_CJ70"
$PN"CJ70"5;
"VSS_CJ68"
$PN"CJ68"5;
"VSS_CJ65"
$PN"CJ65"5;
"VSS_CJ56"
$PN"CJ56"5;
"VSS_CJ45"
$PN"CJ45"5;
"VSS_CJ42"
$PN"CJ42"5;
"VSS_CJ41"
$PN"CJ41"5;
"VSS_CJ40"
$PN"CJ40"5;
"VSS_CJ36"
$PN"CJ36"5;
"VSS_CJ35"
$PN"CJ35"5;
"VSS_CJ18"
$PN"CJ18"5;
"VSS_CJ15"
$PN"CJ15"5;
"VSS_CJ13"
$PN"CJ13"5;
"VSS_CJ11"
$PN"CJ11"5;
"VSS_CJ8"
$PN"CJ8"5;
"VSS_CJ6"
$PN"CJ6"5;
"VSS_CH66"
$PN"CH66"5;
"VSS_CH64"
$PN"CH64"5;
"VSS_CH61"
$PN"CH61"5;
"VSS_CH59"
$PN"CH59"5;
"VSS_CH57"
$PN"CH57"5;
"VSS_CH54"
$PN"CH54"5;
"VSS_CH37"
$PN"CH37"5;
"VSS_CH34"
$PN"CH34"5;
"VSS_CH31"
$PN"CH31"5;
"VSS_CH28"
$PN"CH28"5;
"VSS_CH25"
$PN"CH25"5;
"VSS_CH22"
$PN"CH22"5;
"VSS_CH8"
$PN"CH8"5;
"VSS_CH5"
$PN"CH5"5;
"VSS_CH3"
$PN"CH3"5;
"VSS_CG75"
$PN"CG75"5;
"VSS_CG70"
$PN"CG70"5;
"VSS_CG68"
$PN"CG68"5;
"VSS_CG63"
$PN"CG63"5;
"VSS_CG61"
$PN"CG61"5;
"VSS_CG56"
$PN"CG56"5;
"VSS_CG54"
$PN"CG54"5;
"VSS_CG51"
$PN"CG51"5;
"VSS_CG48"
$PN"CG48"5;
"VSS_CG45"
$PN"CG45"5;
"VSS_CG34"
$PN"CG34"5;
"VSS_CG31"
$PN"CG31"5;
"VSS_CG28"
$PN"CG28"5;
"VSS_CG25"
$PN"CG25"5;
"VSS_CG22"
$PN"CG22"5;
"VSS_CG20"
$PN"CG20"5;
"VSS_CG15"
$PN"CG15"5;
"VSS_CG13"
$PN"CG13"5;
"VSS_CG8"
$PN"CG8"5;
"VSS_CG6"
$PN"CG6"5;
"VSS_CG1"
$PN"CG1"5;
"VSS_CF73"
$PN"CF73"5;
"VSS_CF71"
$PN"CF71"5;
"VSS_CF68"
$PN"CF68"5;
"VSS_CF66"
$PN"CF66"5;
"VSS_CF64"
$PN"CF64"5;
"VSS_CF61"
$PN"CF61"5;
"VSS_CF59"
$PN"CF59"5;
"VSS_CF57"
$PN"CF57"5;
"VSS_CF53"
$PN"CF53"5;
"VSS_CF52"
$PN"CF52"5;
"VSS_CF51"
$PN"CF51"5;
"VSS_CF50"
$PN"CF50"5;
"VSS_CF49"
$PN"CF49"5;
"VSS_CF48"
$PN"CF48"5;
"VSS_CF47"
$PN"CF47"5;
"VSS_CF45"
$PN"CF45"5;
"VSS_CF44"
$PN"CF44"5;
"VSS_CF43"
$PN"CF43"5;
"VSS_CF42"
$PN"CF42"5;
"VSS_CF39"
$PN"CF39"5;
"VSS_CF37"
$PN"CF37"5;
"VSS_CF34"
$PN"CF34"5;
"VSS_CH19"
$PN"CH19"5;
"VSS_CH51"
$PN"CH51"5;
"VSS_CJ4"
$PN"CJ4"5;
"VSS_CL28"
$PN"CL28"6;
"VSS_CL54"
$PN"CL54"6;
"VSS_CM5"
$PN"CM5"6;
"VSS_CM27"
$PN"CM27"6;
"VSS_CM43"
$PN"CM43"6;
"VSS_CH17"
$PN"CH17"5;
"VSS_CH48"
$PN"CH48"5;
"VSS_CJ1"
$PN"CJ1"5;
"VSS_CJ34"
$PN"CJ34"5;
"VSS_CL51"
$PN"CL51"6;
"VSS_CM3"
$PN"CM3"6;
"VSS_CM26"
$PN"CM26"6;
"VSS_CM42"
$PN"CM42"6;
"VSS_CH15"
$PN"CH15"5;
"VSS_CH45"
$PN"CH45"5;
"VSS_CH73"
$PN"CH73"5;
"VSS_CJ31"
$PN"CJ31"5;
"VSS_CJ63"
$PN"CJ63"5;
"VSS_CL75"
$PN"CL75"6;
"VSS_CM25"
$PN"CM25"6;
"VSS_CM39"
$PN"CM39"6;
"VSS_CM66"
$PN"CM66"6;
"VSS_CH12"
$PN"CH12"5;
"VSS_CH42"
$PN"CH42"5;
"VSS_CH71"
$PN"CH71"5;
"VSS_CJ23"
$PN"CJ23"5;
"VSS_CJ61"
$PN"CJ61"5;
"VSS_CK17"
$PN"CK17"5;
"VSS_CM24"
$PN"CM24"6;
"VSS_CM37"
$PN"CM37"6;
"VSS_CM64"
$PN"CM64"6;
"VSS_CN22"
$PN"CN22"6;
"VSS_CH10"
$PN"CH10"5;
"VSS_CH39"
$PN"CH39"5;
"VSS_CH68"
$PN"CH68"5;
"VSS_CJ20"
$PN"CJ20"5;
"VSS_CJ58"
$PN"CJ58"5;
"VSS_CK15"
$PN"CK15"5;
"VSS_CK33"
$PN"CK33"5;
"VSS_CM34"
$PN"CM34"6;
"VSS_CM61"
$PN"CM61"6;
"VSS_CN20"
$PN"CN20"6;
"VSS_CN56"
$PN"CN56"6;
%"GENOA_SP5"
"39","(-1600,3450)","0","pure_quanta","I16";
;
LOCATION"U25"
$SEC"39"
CDS_SEC"39"
PART_TYPE"SMLF"
MATERIAL"IO"
VALUE"SOCKET6096_13568-001"
NEEDS_NO_SIZE"TRUE"
CDS_LMAN_SYM_OUTLINE"-400,3050,400,-3050"
CDS_LIB"pure_quanta"
PART_NUMBER"DGA^6000030";
"VSS_DA70"
$PN"DA70"7;
"VSS_DA68"
$PN"DA68"7;
"VSS_DA65"
$PN"DA65"7;
"VSS_DA63"
$PN"DA63"7;
"VSS_DA61"
$PN"DA61"7;
"VSS_DA58"
$PN"DA58"7;
"VSS_DA42"
$PN"DA42"7;
"VSS_DA34"
$PN"DA34"7;
"VSS_DA31"
$PN"DA31"7;
"VSS_DA28"
$PN"DA28"7;
"VSS_DA25"
$PN"DA25"7;
"VSS_DA22"
$PN"DA22"7;
"VSS_DA11"
$PN"DA11"7;
"VSS_DA8"
$PN"DA8"7;
"VSS_DA6"
$PN"DA6"7;
"VSS_DA4"
$PN"DA4"7;
"VSS_DA1"
$PN"DA1"7;
"VSS_CY73"
$PN"CY73"7;
"VSS_CY71"
$PN"CY71"7;
"VSS_CY61"
$PN"CY61"7;
"VSS_CY59"
$PN"CY59"7;
"VSS_CY53"
$PN"CY53"7;
"VSS_CY52"
$PN"CY52"7;
"VSS_CY51"
$PN"CY51"7;
"VSS_CY50"
$PN"CY50"7;
"VSS_CY49"
$PN"CY49"7;
"VSS_CY46"
$PN"CY46"7;
"VSS_CY45"
$PN"CY45"7;
"VSS_CY44"
$PN"CY44"7;
"VSS_CY43"
$PN"CY43"7;
"VSS_CY42"
$PN"CY42"7;
"VSS_CY39"
$PN"CY39"7;
"VSS_CY37"
$PN"CY37"7;
"VSS_CY34"
$PN"CY34"7;
"VSS_CY33"
$PN"CY33"7;
"VSS_CY31"
$PN"CY31"7;
"VSS_CY30"
$PN"CY30"7;
"VSS_CY29"
$PN"CY29"7;
"VSS_CY28"
$PN"CY28"7;
"VSS_CY27"
$PN"CY27"7;
"VSS_CY26"
$PN"CY26"7;
"VSS_CY25"
$PN"CY25"7;
"VSS_CY24"
$PN"CY24"7;
"VSS_CY23"
$PN"CY23"7;
"VSS_CY19"
$PN"CY19"7;
"VSS_CY17"
$PN"CY17"7;
"VSS_CY15"
$PN"CY15"7;
"VSS_CY12"
$PN"CY12"7;
"VSS_CY10"
$PN"CY10"7;
"VSS_CY8"
$PN"CY8"7;
"VSS_CY5"
$PN"CY5"7;
"VSS_CY3"
$PN"CY3"7;
"VSS_CW75"
$PN"CW75"7;
"VSS_CW70"
$PN"CW70"7;
"VSS_CW68"
$PN"CW68"7;
"VSS_CW63"
$PN"CW63"7;
"VSS_CW61"
$PN"CW61"7;
"VSS_CW56"
$PN"CW56"7;
"VSS_CW54"
$PN"CW54"7;
"VSS_CW51"
$PN"CW51"7;
"VSS_CW48"
$PN"CW48"7;
"VSS_CW45"
$PN"CW45"7;
"VSS_CW42"
$PN"CW42"7;
"VSS_CW41"
$PN"CW41"7;
"VSS_CW40"
$PN"CW40"7;
"VSS_CW36"
$PN"CW36"7;
"VSS_CW35"
$PN"CW35"7;
"VSS_CW20"
$PN"CW20"7;
"VSS_CW15"
$PN"CW15"7;
"VSS_CW13"
$PN"CW13"7;
"VSS_CW8"
$PN"CW8"7;
"VSS_CW6"
$PN"CW6"7;
"VSS_CW1"
$PN"CW1"7;
"VSS_CV61"
$PN"CV61"7;
"VSS_CV59"
$PN"CV59"7;
"VSS_CV57"
$PN"CV57"7;
"VSS_CV54"
$PN"CV54"7;
"VSS_CV51"
$PN"CV51"7;
"VSS_CV48"
$PN"CV48"7;
"VSS_CV31"
$PN"CV31"7;
"VSS_CV28"
$PN"CV28"7;
"VSS_CV25"
$PN"CV25"7;
"VSS_CV22"
$PN"CV22"7;
"VSS_CV19"
$PN"CV19"7;
"VSS_CV17"
$PN"CV17"7;
"VSS_CV3"
$PN"CV3"8;
"VSS_CU75"
$PN"CU75"8;
"VSS_CU72"
$PN"CU72"8;
"VSS_CU70"
$PN"CU70"8;
"VSS_CU68"
$PN"CU68"8;
"VSS_CU65"
$PN"CU65"8;
"VSS_CU54"
$PN"CU54"8;
"VSS_CU51"
$PN"CU51"8;
"VSS_CU48"
$PN"CU48"8;
"VSS_CU45"
$PN"CU45"8;
"VSS_CU42"
$PN"CU42"8;
"VSS_CU34"
$PN"CU34"8;
"VSS_CU31"
$PN"CU31"8;
"VSS_CU20"
$PN"CU20"8;
"VSS_CU18"
$PN"CU18"8;
"VSS_CU15"
$PN"CU15"8;
"VSS_CU13"
$PN"CU13"8;
"VSS_CU11"
$PN"CU11"8;
"VSS_CU8"
$PN"CU8"8;
"VSS_CU6"
$PN"CU6"8;
"VSS_CU4"
$PN"CU4"8;
"VSS_CT68"
$PN"CT68"8;
"VSS_CT66"
$PN"CT66"8;
"VSS_CT61"
$PN"CT61"8;
"VSS_CT59"
$PN"CT59"8;
"VSS_CT53"
$PN"CT53"8;
"VSS_CT51"
$PN"CT51"8;
"VSS_CT50"
$PN"CT50"8;
"VSS_CT49"
$PN"CT49"8;
"VSS_CT47"
$PN"CT47"8;
"VSS_CT46"
$PN"CT46"8;
"VSS_CT45"
$PN"CT45"8;
"VSS_CT44"
$PN"CT44"8;
"VSS_CT43"
$PN"CT43"8;
"VSS_CT42"
$PN"CT42"8;
"VSS_CT39"
$PN"CT39"8;
"VSS_CT37"
$PN"CT37"8;
"VSS_CT34"
$PN"CT34"8;
"VSS_CT33"
$PN"CT33"8;
"VSS_CT32"
$PN"CT32"8;
"VSS_CT31"
$PN"CT31"8;
"VSS_CT30"
$PN"CT30"8;
"VSS_CT29"
$PN"CT29"8;
"VSS_CT28"
$PN"CT28"8;
"VSS_CT27"
$PN"CT27"8;
"VSS_CT26"
$PN"CT26"8;
"VSS_CT25"
$PN"CT25"8;
"VSS_CT24"
$PN"CT24"8;
"VSS_CT23"
$PN"CT23"8;
"VSS_CT17"
$PN"CT17"8;
"VSS_CR72"
$PN"CR72"8;
"VSS_CR70"
$PN"CR70"8;
"VSS_CR68"
$PN"CR68"8;
"VSS_CR65"
$PN"CR65"8;
"VSS_CR63"
$PN"CR63"8;
"VSS_CR61"
$PN"CR61"8;
"VSS_CR45"
$PN"CR45"8;
"VSS_CR42"
$PN"CR42"8;
"VSS_CR41"
$PN"CR41"8;
"VSS_CR40"
$PN"CR40"8;
"VSS_CR36"
$PN"CR36"8;
"VSS_CR35"
$PN"CR35"8;
"VSS_CR20"
$PN"CR20"8;
"VSS_CR18"
$PN"CR18"8;
"VSS_CR15"
$PN"CR15"8;
"VSS_CR13"
$PN"CR13"8;
"VSS_CR11"
$PN"CR11"8;
"VSS_CR8"
$PN"CR8"8;
"VSS_CP68"
$PN"CP68"8;
"VSS_CP66"
$PN"CP66"8;
"VSS_CP64"
$PN"CP64"8;
"VSS_CP61"
$PN"CP61"8;
"VSS_CP59"
$PN"CP59"8;
"VSS_CP57"
$PN"CP57"8;
"VSS_CP39"
$PN"CP39"8;
"VSS_CP37"
$PN"CP37"8;
"VSS_CP34"
$PN"CP34"8;
"VSS_CP31"
$PN"CP31"8;
"VSS_CP28"
$PN"CP28"8;
"VSS_CP25"
$PN"CP25"8;
"VSS_DA54"
$PN"DA54"7;
"VSS_DA51"
$PN"DA51"7;
"VSS_DA48"
$PN"DA48"7;
"VSS_DA45"
$PN"DA45"7;
"VSS_DA20"
$PN"DA20"7;
"VSS_DA18"
$PN"DA18"7;
"VSS_DA15"
$PN"DA15"7;
"VSS_DA13"
$PN"DA13"7;
"VSS_CY68"
$PN"CY68"7;
"VSS_CY66"
$PN"CY66"7;
"VSS_CY64"
$PN"CY64"7;
"VSS_CY48"
$PN"CY48"7;
"VSS_CY47"
$PN"CY47"7;
"VSS_CY32"
$PN"CY32"7;
"VSS_CW34"
$PN"CW34"7;
"VSS_CW31"
$PN"CW31"7;
"VSS_CW28"
$PN"CW28"7;
"VSS_CW25"
$PN"CW25"7;
"VSS_CW22"
$PN"CW22"7;
"VSS_CV73"
$PN"CV73"7;
"VSS_CV71"
$PN"CV71"7;
"VSS_CV68"
$PN"CV68"7;
"VSS_CV66"
$PN"CV66"7;
"VSS_CV64"
$PN"CV64"7;
"VSS_CV45"
$PN"CV45"7;
"VSS_CV42"
$PN"CV42"7;
"VSS_CV39"
$PN"CV39"7;
"VSS_CV37"
$PN"CV37"7;
"VSS_CV34"
$PN"CV34"7;
"VSS_CV15"
$PN"CV15"7;
"VSS_CV12"
$PN"CV12"7;
"VSS_CV10"
$PN"CV10"7;
"VSS_CV8"
$PN"CV8"8;
"VSS_CV5"
$PN"CV5"8;
"VSS_CU63"
$PN"CU63"8;
"VSS_CU61"
$PN"CU61"8;
"VSS_CU56"
$PN"CU56"8;
"VSS_CU28"
$PN"CU28"8;
"VSS_CU25"
$PN"CU25"8;
"VSS_CU22"
$PN"CU22"8;
"VSS_CU1"
$PN"CU1"8;
"VSS_CT73"
$PN"CT73"8;
"VSS_CT48"
$PN"CT48"8;
"VSS_CT15"
$PN"CT15"8;
"VSS_CT10"
$PN"CT10"8;
"VSS_CT8"
$PN"CT8"8;
"VSS_CT3"
$PN"CT3"8;
"VSS_CR75"
$PN"CR75"8;
"VSS_CR58"
$PN"CR58"8;
"VSS_CR56"
$PN"CR56"8;
"VSS_CR54"
$PN"CR54"8;
"VSS_CR51"
$PN"CR51"8;
"VSS_CR48"
$PN"CR48"8;
"VSS_CR34"
$PN"CR34"8;
"VSS_CR31"
$PN"CR31"8;
"VSS_CR28"
$PN"CR28"8;
"VSS_CR25"
$PN"CR25"8;
"VSS_CR22"
$PN"CR22"8;
"VSS_CR6"
$PN"CR6"8;
"VSS_CR4"
$PN"CR4"8;
"VSS_CR1"
$PN"CR1"8;
"VSS_CP73"
$PN"CP73"8;
"VSS_CP71"
$PN"CP71"8;
"VSS_CP54"
$PN"CP54"8;
"VSS_CP51"
$PN"CP51"8;
"VSS_CP48"
$PN"CP48"8;
"VSS_CP45"
$PN"CP45"8;
"VSS_CP42"
$PN"CP42"8;
"VSS_CP22"
$PN"CP22"8;
%"UNIVERSAL_GND"
"1","(-7050,425)","0","pure_quanta_power","I17";
;
CDS_LIB"pure_quanta_power"
HDL_POWER"GND";
"A"2;
%"UNIVERSAL_GND"
"1","(-8500,400)","0","pure_quanta_power","I18";
;
CDS_LIB"pure_quanta_power"
HDL_POWER"GND";
"A"1;
%"UNIVERSAL_GND"
"1","(-6475,425)","0","pure_quanta_power","I19";
;
CDS_LIB"pure_quanta_power"
HDL_POWER"GND";
"A"3;
%"UNIVERSAL_GND"
"1","(-5025,425)","0","pure_quanta_power","I20";
;
CDS_LIB"pure_quanta_power"
HDL_POWER"GND";
"A"4;
%"UNIVERSAL_GND"
"1","(-4400,425)","0","pure_quanta_power","I21";
;
CDS_LIB"pure_quanta_power"
HDL_POWER"GND";
"A"5;
%"UNIVERSAL_GND"
"1","(-2950,400)","0","pure_quanta_power","I22";
;
CDS_LIB"pure_quanta_power"
HDL_POWER"GND";
"A"6;
%"UNIVERSAL_GND"
"1","(-875,400)","0","pure_quanta_power","I23";
;
CDS_LIB"pure_quanta_power"
HDL_POWER"GND";
"A"8;
%"UNIVERSAL_GND"
"1","(-2325,400)","0","pure_quanta_power","I24";
;
CDS_LIB"pure_quanta_power"
HDL_POWER"GND";
"A"7;
END.
